# T6G (Grand Teton) — schematic netlist excerpt (pin names and nets, part order shuffled) for the footprints in the layout excerpt that follows; sources: Cadence DE-HDL packaged netlist, KiCad conversion of 04192023_DAF0TMB3IC0_F0TG_MB_C_brd_V02_OCP.brd

PR101  Q_RES  5.6 1% CHIP  pkg 0402LF  page 205 : A = SW_PVDDIO_P0_BOOT1 ; B = SW_PVDDIO_P0_BOOT1_R
R641  Q_RES  51.1 1% EMPTY  pkg 0201LF  page 353 : A = CLK_100M_RETIMER_CPU1_P3_DN ; B = GND

(kicad_pcb
	(version 20260206)
	(generator "pcbnew")
	(generator_version "10.0")
	(general
		(thickness 1.6)
		(legacy_teardrops no)
	)
	(paper "A4")
	(title_block
		(title "04192023_DAF0TMB3IC0_F0TG_MB_C_brd_V02_OCP.brd")
		(comment 1 "Grand Teton / footprints 391-392 of 8354")
	)
	(layers
		(0 "F.Cu" signal "TOP")
		(4 "In1.Cu" signal "GND")
		(6 "In2.Cu" signal "IN1")
		(8 "In3.Cu" signal "GND1")
		(10 "In4.Cu" signal "IN2")
		(12 "In5.Cu" signal "GND2")
		(14 "In6.Cu" signal "IN3")
		(16 "In7.Cu" signal "GND3")
		(18 "In8.Cu" signal "VCC")
		(20 "In9.Cu" signal "VCC1")
		(22 "In10.Cu" signal "GND4")
		(24 "In11.Cu" signal "IN4")
		(26 "In12.Cu" signal "GND5")
		(28 "In13.Cu" signal "IN5")
		(30 "In14.Cu" signal "GND6")
		(32 "In15.Cu" signal "IN6")
		(34 "In16.Cu" signal "GND7")
		(2 "B.Cu" signal "BOTTOM")
		(9 "F.Adhes" user "F.Adhesive")
		(11 "B.Adhes" user "B.Adhesive")
		(13 "F.Paste" user "Package Geometry/Pastemask Top")
		(15 "B.Paste" user "Package Geometry/Pastemask Bottom")
		(5 "F.SilkS" user "Ref Des/Silkscreen Top")
		(7 "B.SilkS" user "Ref Des/Silkscreen Bottom")
		(1 "F.Mask" user "Board Geometry/Soldermask Top")
		(3 "B.Mask" user "Board Geometry/Soldermask Bottom")
		(17 "Dwgs.User" user "User.Drawings")
		(19 "Cmts.User" user "User.Comments")
		(21 "Eco1.User" user "User.Eco1")
		(23 "Eco2.User" user "User.Eco2")
		(25 "Edge.Cuts" user "Board Geometry/Outline")
		(27 "Margin" user)
		(31 "F.CrtYd" user "Package Geometry/Place Bound Top")
		(29 "B.CrtYd" user "Package Geometry/Place Bound Bottom")
		(35 "F.Fab" user "Ref Des/Assembly Top")
		(33 "B.Fab" user "Ref Des/Assembly Bottom")
	)
	(footprint ""
		(layer "F.Cu")
		(at 301.124112 -351.368106 90)
		(property "Reference" "PR101"
			(at 0 0 90)
			(layer "F.SilkS")
			(hide yes)
			(effects
				(font
					(size 1.27 1.27)
				)
			)
		)
		(property "Value" ""
			(at 0 0 90)
			(layer "F.Fab")
			(effects
				(font
					(size 1.27 1.27)
				)
			)
		)
		(duplicate_pad_numbers_are_jumpers no)
		(fp_line
			(start 0.7874 -0.4064)
			(end 0.7874 0.4064)
			(stroke
				(width 0.1524)
				(type default)
			)
			(layer "F.SilkS")
		)
		(fp_line
			(start -0.7874 -0.4064)
			(end 0.7874 -0.4064)
			(stroke
				(width 0.1524)
				(type default)
			)
			(layer "F.SilkS")
		)
		(fp_line
			(start 0.7874 0.4064)
			(end -0.7874 0.4064)
			(stroke
				(width 0.1524)
				(type default)
			)
			(layer "F.SilkS")
		)
		(fp_line
			(start -0.7874 0.4064)
			(end -0.7874 -0.4064)
			(stroke
				(width 0.1524)
				(type default)
			)
			(layer "F.SilkS")
		)
		(fp_line
			(start -0.12065 -0.305054)
			(end -0.12065 -0.2794)
			(stroke
				(width 0.1)
				(type default)
			)
			(layer "F.Fab")
		)
		(fp_line
			(start -0.67945 -0.305054)
			(end -0.12065 -0.305054)
			(stroke
				(width 0.1)
				(type default)
			)
			(layer "F.Fab")
		)
		(fp_line
			(start 0.67945 -0.3048)
			(end 0.67945 0.3048)
			(stroke
				(width 0.1)
				(type default)
			)
			(layer "F.Fab")
		)
		(fp_line
			(start 0.12065 -0.3048)
			(end 0.67945 -0.3048)
			(stroke
				(width 0.1)
				(type default)
			)
			(layer "F.Fab")
		)
		(fp_line
			(start 0.12065 -0.2794)
			(end 0.12065 -0.3048)
			(stroke
				(width 0.1)
				(type default)
			)
			(layer "F.Fab")
		)
		(fp_line
			(start -0.12065 -0.2794)
			(end 0.12065 -0.2794)
			(stroke
				(width 0.1)
				(type default)
			)
			(layer "F.Fab")
		)
		(fp_line
			(start 0.120396 0.2794)
			(end -0.12065 0.2794)
			(stroke
				(width 0.1)
				(type default)
			)
			(layer "F.Fab")
		)
		(fp_line
			(start -0.12065 0.2794)
			(end -0.12065 0.3048)
			(stroke
				(width 0.1)
				(type default)
			)
			(layer "F.Fab")
		)
		(fp_line
			(start 0.67945 0.3048)
			(end 0.120396 0.3048)
			(stroke
				(width 0.1)
				(type default)
			)
			(layer "F.Fab")
		)
		(fp_line
			(start 0.120396 0.3048)
			(end 0.120396 0.2794)
			(stroke
				(width 0.1)
				(type default)
			)
			(layer "F.Fab")
		)
		(fp_line
			(start -0.12065 0.3048)
			(end -0.67945 0.3048)
			(stroke
				(width 0.1)
				(type default)
			)
			(layer "F.Fab")
		)
		(fp_line
			(start -0.67945 0.3048)
			(end -0.67945 -0.305054)
			(stroke
				(width 0.1)
				(type default)
			)
			(layer "F.Fab")
		)
		(pad "1" smd circle
			(at -0.40005 0 90)
			(size 0 0)
			(layers "F.Cu" "F.Mask" "F.Paste")
			(net "SW_PVDDIO_P0_BOOT1")
		)
		(pad "2" smd circle
			(at 0.40005 0 90)
			(size 0 0)
			(layers "F.Cu" "F.Mask" "F.Paste")
			(net "SW_PVDDIO_P0_BOOT1_R")
		)
	)
	(footprint ""
		(layer "F.Cu")
		(at 110.643924 -386.684774 -90)
		(property "Reference" "R641"
			(at 0 0 270)
			(layer "F.SilkS")
			(hide yes)
			(effects
				(font
					(size 1.27 1.27)
				)
			)
		)
		(property "Value" ""
			(at 0 0 270)
			(layer "F.Fab")
			(effects
				(font
					(size 1.27 1.27)
				)
			)
		)
		(duplicate_pad_numbers_are_jumpers no)
		(fp_line
			(start -0.32512 0.175006)
			(end -0.32512 -0.175006)
			(stroke
				(width 0.1)
				(type default)
			)
			(layer "F.Fab")
		)
		(fp_line
			(start 0.32512 0.175006)
			(end -0.32512 0.175006)
			(stroke
				(width 0.1)
				(type default)
			)
			(layer "F.Fab")
		)
		(fp_line
			(start -0.32512 -0.175006)
			(end 0.32512 -0.175006)
			(stroke
				(width 0.1)
				(type default)
			)
			(layer "F.Fab")
		)
		(fp_line
			(start 0.32512 -0.175006)
			(end 0.32512 0.175006)
			(stroke
				(width 0.1)
				(type default)
			)
			(layer "F.Fab")
		)
		(pad "1" smd rect
			(at -0.2667 0 270)
			(size 0.3048 0.381)
			(layers "F.Cu" "F.Mask" "F.Paste")
			(net "CLK_100M_RETIMER_CPU1_P3_DN")
		)
		(pad "2" smd rect
			(at 0.2667 0 90)
			(size 0.3048 0.381)
			(layers "F.Cu" "F.Mask" "F.Paste")
			(net "GND")
		)
	)
)
